# BASEBOARD_FAB2 (Tioga Pass) — schematic netlist excerpt (pin names and nets, part order shuffled) for the footprints in the layout excerpt that follows; sources: Cadence DE-HDL packaged netlist, KiCad conversion of Wiwynn_Tioga_Pass_MB.brd

C2G16  CAP  100UF 4V 20% X5R  pkg 0805  page 225 : A = PVDDQ_GHJ ; B = GND
C3F4  CAP  10UF 4V 20% X6S  pkg 0603LF  page 233 : A = PVPP_GHJ ; B = GND
R4E2  RES  3.16K 1% CHIP  pkg 0402  page 213 : A = VR_PVCCIO_CPU1_XADDR2 ; B = GND

(kicad_pcb
	(version 20260206)
	(generator "pcbnew")
	(generator_version "10.0")
	(general
		(thickness 1.6)
		(legacy_teardrops no)
	)
	(paper "A4")
	(title_block
		(title "Wiwynn_Tioga_Pass_MB.brd")
		(comment 1 "Tioga Pass / footprints 1878-1880 of 4770")
	)
	(layers
		(0 "F.Cu" signal "TOP")
		(4 "In1.Cu" signal "L2GND")
		(6 "In2.Cu" signal "L3")
		(8 "In3.Cu" signal "L4GND")
		(10 "In4.Cu" signal "L5")
		(12 "In5.Cu" signal "L6GND")
		(14 "In6.Cu" signal "L7VCC")
		(16 "In7.Cu" signal "L8VCC")
		(18 "In8.Cu" signal "L9GND")
		(20 "In9.Cu" signal "L10")
		(22 "In10.Cu" signal "L11GND")
		(24 "In11.Cu" signal "L12")
		(26 "In12.Cu" signal "L13GND")
		(2 "B.Cu" signal "BOTTOM")
		(9 "F.Adhes" user "F.Adhesive")
		(11 "B.Adhes" user "B.Adhesive")
		(13 "F.Paste" user "Package Geometry/Pastemask Top")
		(15 "B.Paste" user "Package Geometry/Pastemask Bottom")
		(5 "F.SilkS" user "Ref Des/Silkscreen Top")
		(7 "B.SilkS" user "Ref Des/Silkscreen Bottom")
		(1 "F.Mask" user "Board Geometry/Soldermask Top")
		(3 "B.Mask" user "Board Geometry/Soldermask Bottom")
		(17 "Dwgs.User" user "User.Drawings")
		(19 "Cmts.User" user "User.Comments")
		(21 "Eco1.User" user "User.Eco1")
		(23 "Eco2.User" user "User.Eco2")
		(25 "Edge.Cuts" user "Board Geometry/Outline")
		(27 "Margin" user)
		(31 "F.CrtYd" user "Package Geometry/Place Bound Top")
		(29 "B.CrtYd" user "Package Geometry/Place Bound Bottom")
		(35 "F.Fab" user "Ref Des/Assembly Top")
		(33 "B.Fab" user "Ref Des/Assembly Bottom")
	)
	(footprint ""
		(layer "F.Cu")
		(at 155.1051 -22.7457 90)
		(property "Reference" "C3F4"
			(at 0 0 90)
			(layer "F.SilkS")
			(hide yes)
			(effects
				(font
					(size 1.27 1.27)
				)
			)
		)
		(property "Value" ""
			(at 0 0 90)
			(layer "F.Fab")
			(effects
				(font
					(size 1.27 1.27)
				)
			)
		)
		(duplicate_pad_numbers_are_jumpers no)
		(fp_poly
			(pts
				(xy -0.4953 -0.2032) (xy 0.4953 -0.2032) (xy 0.4953 1.6002) (xy -0.4953 1.6002)
			)
			(stroke
				(width 0)
				(type default)
			)
			(fill no)
			(layer "F.CrtYd")
		)
		(fp_line
			(start 0.4953 -0.2032)
			(end 0.4953 1.6002)
			(stroke
				(width 0.1)
				(type default)
			)
			(layer "F.Fab")
		)
		(fp_line
			(start -0.4953 -0.2032)
			(end 0.4953 -0.2032)
			(stroke
				(width 0.1)
				(type default)
			)
			(layer "F.Fab")
		)
		(fp_line
			(start 0.4953 1.6002)
			(end -0.4953 1.6002)
			(stroke
				(width 0.1)
				(type default)
			)
			(layer "F.Fab")
		)
		(fp_line
			(start -0.4953 1.6002)
			(end -0.4953 -0.2032)
			(stroke
				(width 0.1)
				(type default)
			)
			(layer "F.Fab")
		)
		(pad "1" smd rect
			(at 0 0 90)
			(size 0.762 0.889)
			(layers "F.Cu" "F.Mask" "F.Paste")
			(net "PVPP_GHJ")
		)
		(pad "2" smd rect
			(at 0 1.397 90)
			(size 0.762 0.889)
			(layers "F.Cu" "F.Mask" "F.Paste")
			(net "GND")
		)
		(zone
			(layer "F.Cu")
			(hatch none 0.5)
			(connect_pads
				(clearance 0)
			)
			(min_thickness 0.25)
			(keepout
				(tracks not_allowed)
				(vias allowed)
				(pads allowed)
				(copperpour not_allowed)
				(footprints allowed)
			)
			(placement
				(enabled no)
				(sheetname "")
			)
			(fill
				(thermal_gap 0.5)
				(thermal_bridge_width 0.5)
				(island_removal_mode 0)
			)
			(polygon
				(pts
					(xy 155.5496 -22.3647) (xy 155.5496 -23.1267) (xy 156.0576 -23.1267) (xy 156.0576 -22.3647)
				)
			)
		)
	)
	(footprint ""
		(layer "F.Cu")
		(at 173.736 -63.831978 90)
		(property "Reference" "R4E2"
			(at 0 0 90)
			(layer "F.SilkS")
			(hide yes)
			(effects
				(font
					(size 1.27 1.27)
				)
			)
		)
		(property "Value" ""
			(at 0 0 90)
			(layer "F.Fab")
			(effects
				(font
					(size 1.27 1.27)
				)
			)
		)
		(duplicate_pad_numbers_are_jumpers no)
		(fp_poly
			(pts
				(xy -0.2794 -0.1016) (xy 0.2794 -0.1016) (xy 0.2794 0.9906) (xy -0.2794 0.9906)
			)
			(stroke
				(width 0)
				(type default)
			)
			(fill no)
			(layer "F.CrtYd")
		)
		(fp_line
			(start 0.2794 -0.1016)
			(end -0.2794 -0.1016)
			(stroke
				(width 0.1)
				(type default)
			)
			(layer "F.Fab")
		)
		(fp_line
			(start -0.2794 -0.1016)
			(end -0.2794 0.9906)
			(stroke
				(width 0.1)
				(type default)
			)
			(layer "F.Fab")
		)
		(fp_line
			(start 0.2794 0.9906)
			(end 0.2794 -0.1016)
			(stroke
				(width 0.1)
				(type default)
			)
			(layer "F.Fab")
		)
		(fp_line
			(start -0.2794 0.9906)
			(end 0.2794 0.9906)
			(stroke
				(width 0.1)
				(type default)
			)
			(layer "F.Fab")
		)
		(pad "1" smd rect
			(at 0 0 90)
			(size 0.508 0.508)
			(layers "F.Cu" "F.Mask" "F.Paste")
			(net "VR_PVCCIO_CPU1_XADDR2")
		)
		(pad "2" smd rect
			(at 0 0.889 90)
			(size 0.508 0.508)
			(layers "F.Cu" "F.Mask" "F.Paste")
			(net "GND")
		)
		(zone
			(layer "F.Cu")
			(hatch none 0.5)
			(connect_pads
				(clearance 0)
			)
			(min_thickness 0.25)
			(keepout
				(tracks allowed)
				(vias not_allowed)
				(pads allowed)
				(copperpour not_allowed)
				(footprints allowed)
			)
			(placement
				(enabled no)
				(sheetname "")
			)
			(fill
				(thermal_gap 0.5)
				(thermal_bridge_width 0.5)
				(island_removal_mode 0)
			)
			(polygon
				(pts
					(xy 173.99 -63.577978) (xy 173.99 -64.085978) (xy 174.371 -64.085978) (xy 174.371 -63.577978)
				)
			)
		)
		(zone
			(layer "F.Cu")
			(hatch none 0.5)
			(connect_pads
				(clearance 0)
			)
			(min_thickness 0.25)
			(keepout
				(tracks not_allowed)
				(vias allowed)
				(pads allowed)
				(copperpour not_allowed)
				(footprints allowed)
			)
			(placement
				(enabled no)
				(sheetname "")
			)
			(fill
				(thermal_gap 0.5)
				(thermal_bridge_width 0.5)
				(island_removal_mode 0)
			)
			(polygon
				(pts
					(xy 174.371 -63.577978) (xy 174.371 -64.085978) (xy 173.99 -64.085978) (xy 173.99 -63.577978)
				)
			)
		)
	)
	(footprint ""
		(layer "F.Cu")
		(at 94.308168 -3.321812 90)
		(property "Reference" "C2G16"
			(at 0 0 90)
			(layer "F.SilkS")
			(hide yes)
			(effects
				(font
					(size 1.27 1.27)
				)
			)
		)
		(property "Value" ""
			(at 0 0 90)
			(layer "F.Fab")
			(effects
				(font
					(size 1.27 1.27)
				)
			)
		)
		(duplicate_pad_numbers_are_jumpers no)
		(fp_poly
			(pts
				(xy -0.7239 -0.2159) (xy 0.7239 -0.2159) (xy 0.7239 1.9939) (xy -0.7239 1.9939)
			)
			(stroke
				(width 0)
				(type default)
			)
			(fill no)
			(layer "F.CrtYd")
		)
		(fp_line
			(start 0.7239 -0.2159)
			(end -0.7239 -0.2159)
			(stroke
				(width 0.1)
				(type default)
			)
			(layer "F.Fab")
		)
		(fp_line
			(start -0.7239 -0.2159)
			(end -0.7239 1.9939)
			(stroke
				(width 0.1)
				(type default)
			)
			(layer "F.Fab")
		)
		(fp_line
			(start 0.7239 1.9939)
			(end 0.7239 -0.2159)
			(stroke
				(width 0.1)
				(type default)
			)
			(layer "F.Fab")
		)
		(fp_line
			(start -0.7239 1.9939)
			(end 0.7239 1.9939)
			(stroke
				(width 0.1)
				(type default)
			)
			(layer "F.Fab")
		)
		(pad "1" smd rect
			(at 0 0 90)
			(size 1.27 1.016)
			(layers "F.Cu" "F.Mask" "F.Paste")
			(net "PVDDQ_GHJ")
		)
		(pad "2" smd rect
			(at 0 1.778 90)
			(size 1.27 1.016)
			(layers "F.Cu" "F.Mask" "F.Paste")
			(net "GND")
		)
		(zone
			(layer "F.Cu")
			(hatch none 0.5)
			(connect_pads
				(clearance 0)
			)
			(min_thickness 0.25)
			(keepout
				(tracks not_allowed)
				(vias allowed)
				(pads allowed)
				(copperpour not_allowed)
				(footprints allowed)
			)
			(placement
				(enabled no)
				(sheetname "")
			)
			(fill
				(thermal_gap 0.5)
				(thermal_bridge_width 0.5)
				(island_removal_mode 0)
			)
			(polygon
				(pts
					(xy 94.816168 -2.686812) (xy 94.816168 -3.956812) (xy 95.578168 -3.956812) (xy 95.578168 -2.686812)
				)
			)
		)
	)
)
